FILE_TYPE = MULTI_PHYS_TABLE;

PART 'MOSFET_PCH_GDS_ESD_PROTECTED'

{========================================================================================}
:VALUE        | PART_TYPE | MATERIAL | PART_NUMBER    = STANDARD | LIFECYCLE     | PART_NUMBER   | JEDEC_TYPE          | DESCRIPTION                                | MANUFTR | MANUF_PN     | RD_CMPLS_LVL | CMPLS_LVL | CLASS | DIP_SMD | FP_ECN | FROM_PJ        | DATA                 | EE_CHECK_LIST | STATUS | PSL | PREFERENCE | CREATOR | CREATEDAY  ;
{========================================================================================}
 'AO3415'     | 'SMLF'    | 'IC'     | 'BAM34150001'(!) = ''       | 'End of Life' | 'BAM34150001' |'SOT23_GDSXA_EOL'| 'TRANS MOSFET AO3415(-20V.-4A)SOT-23'      | 'AOS'   | 'AO3415'     | 'EU'         | 'EU'      | 'IC'  | ''      | ''     | 'T6R-WADE'     | 'AO3415.pdf'         | ''            | ''     | ''  | ''         | ''      | '20190311'
 'AO3415'     | 'SMLF'    | 'EMPTY'  | 'BAM34150001'(!) = ''       | 'End of Life' | 'BAM34150001' |'SOT23_GDSXA_EOL'| 'TRANS MOSFET AO3415(-20V.-4A)SOT-23'      | 'AOS'   | 'AO3415'     | 'EU'         | 'EU'      | 'IC'  | ''      | ''     | 'T6R-WADE'     | 'AO3415.pdf'         | ''            | ''     | ''  | ''         | ''      | '20190311'
 'DMP2045U-7' | 'SMLF'    | 'IC'     | 'BAM20450000'(!) = ''       | ''            | 'BAM20450000' |'SOT23_GDSXC'| 'TRANS MOS DMP2045U-7(-20V,-4.3A1.2WSOT23' | 'DDS'   | 'DMP2045U-7' | 'EP(V1)'     | ''        | 'IC'  | ''      | ''     | 'F0C-ALEN'     | 'DDS_DMP2045U-7.pdf' | ''            | ''     | ''  | ''         | ''      | '20190313'
 'DMP2045U-7' | 'SMLF'    | 'EMPTY'  | 'BAM20450000'(!) = ''       | ''            | 'BAM20450000' |'SOT23_GDSXC'| 'TRANS MOS DMP2045U-7(-20V,-4.3A1.2WSOT23' | 'DDS'   | 'DMP2045U-7' | 'EP(V1)'     | ''        | 'IC'  | ''      | ''     | 'F0C-ALEN'     | 'DDS_DMP2045U-7.pdf' | ''            | ''     | ''  | ''         | ''      | '20190313'
 'PJA3415AE'  | 'SMLF'    | 'IC'     | 'BAM34150008'(!) = ''       | ''            | 'BAM34150008' |'SOT23_GDSXC'| 'TRANS MOS PJA3415AE(-20V,-4.3A,1.25W)'    | 'PJT'   | 'PJA3415AE'  | 'EP(V1)'     | 'EP(V1)'  | 'IC'  | ''      | ''     | 'S5X-BRIAN'    | 'PJT_PJA3415AE.pdf'  | ''            | ''     | ''  | ''         | ''      | '20190314'
 'PJA3415AE'  | 'SMLF'    | 'EMPTY'  | 'BAM34150008'(!) = ''       | ''            | 'BAM34150008' |'SOT23_GDSXC'| 'TRANS MOS PJA3415AE(-20V,-4.3A,1.25W)'    | 'PJT'   | 'PJA3415AE'  | 'EP(V1)'     | 'EP(V1)'  | 'IC'  | ''      | ''     | 'S5X-BRIAN'    | 'PJT_PJA3415AE.pdf'  | ''            | ''     | ''  | ''         | ''      | '20190314'
 'DMP2035U-7' | 'SMLF'    | 'IC'     | 'BAM20350002'(!) = ''       | ''            | 'BAM20350002' |'SOT23_GDSXC'| 'TRANS MOS DMP2035U-7(-20V,-4.9A,0.81W)'   | 'DDS'   | 'DMP2035U-7' | 'EP(V1)'     | ''        | 'IC'  | ''      | ''     | 'JG7-ALLEN'    | 'DDS_DMP2045U-7.pdf' | ''            | ''     | ''  | ''         | ''      | '20200902'
 'DMP2035U-7' | 'SMLF'    | 'EMPTY'  | 'BAM20350002'(!) = ''       | ''            | 'BAM20350002' |'SOT23_GDSXC'| 'TRANS MOS DMP2035U-7(-20V,-4.9A,0.81W)'   | 'DDS'   | 'DMP2035U-7' | 'EP(V1)'     | ''        | 'IC'  | ''      | ''     | 'JG7-ALLEN'    | 'DDS_DMP2045U-7.pdf' | ''            | ''     | ''  | ''         | ''      | '20200902'
 'RD3P130SP'  | 'SMLF'    | 'IC'     | 'BAM30SP0000'(!) = ''       | ''            | 'BAM30SP0000' |'TO252_GDS_6-6X6-2'| 'TRANS MOS RD3P130SP(100V,+-13A, 20W)'     | 'ROH'   | 'RD3P130SP'  | 'EP(V1)'     | ''        | 'IC'  | ''      | ''     | '2RE-JASON'    | 'ROH_RD3P130SP.pdf'  | ''            | ''     | ''  | ''         | ''      | '20211012'
 'RD3P130SP'  | 'SMLF'    | 'EMPTY'  | 'BAM30SP0000'(!) = ''       | ''            | 'BAM30SP0000' |'TO252_GDS_6-6X6-2'| 'TRANS MOS RD3P130SP(100V,+-13A, 20W)'     | 'ROH'   | 'RD3P130SP'  | 'EP(V1)'     | ''        | 'IC'  | ''      | ''     | '2RE-JASON'    | 'ROH_RD3P130SP.pdf'  | ''            | ''     | ''  | ''         | ''      | '20211012'
 'RSJ250P10'  | 'SMLF'    | 'IC'     | 'BAM0P100000'(!) = ''       | ''            | 'BAM0P100000' |'TO263S_GDS_10-1X9'| 'TRANS MOS RSJ250P10(-100V,25A,50W)'       | 'ROH'   | 'RSJ250P10'  | 'EP(V1)'     | ''        | 'IC'  | ''      | ''     | 'F0T-KEN'      | 'ROH_RSJ250P10.pdf'  | ''            | ''     | ''  | ''         | ''      | '20230218'
 'RSJ250P10'  | 'SMLF'    | 'EMPTY'  | 'BAM0P100000'(!) = ''       | ''            | 'BAM0P100000' |'TO263S_GDS_10-1X9'| 'TRANS MOS RSJ250P10(-100V,25A,50W)'       | 'ROH'   | 'RSJ250P10'  | 'EP(V1)'     | ''        | 'IC'  | ''      | ''     | 'F0T-KEN'      | 'ROH_RSJ250P10.pdf'  | ''            | ''     | ''  | ''         | ''      | '20230218'
 'AOSS21319C' | 'SMLF'    | 'IC'     | 'BAM21310000'(!) = ''       | ''            | 'BAM21310000' |'SOT23_GDSXA'| 'TRANS MOS AOSS21319C (-30V,-2.8A,1.3W)'   | 'AOS'   | 'AOSS21319C' | 'EP(V1)'     | 'EP(V1)'  | 'IC'  | ''      | ''     | 'F0EG-PATRICK' | 'AOS_AOSS21319C.pdf' | ''            | ''     | ''  | ''         | ''      | '20230406'
 'AOSS21319C' | 'SMLF'    | 'EMPTY'  | 'BAM21310000'(!) = ''       | ''            | 'BAM21310000' |'SOT23_GDSXA'| 'TRANS MOS AOSS21319C (-30V,-2.8A,1.3W)'   | 'AOS'   | 'AOSS21319C' | 'EP(V1)'     | 'EP(V1)'  | 'IC'  | ''      | ''     | 'F0EG-PATRICK' | 'AOS_AOSS21319C.pdf' | ''            | ''     | ''  | ''         | ''      | '20230406'

END_PART

END.

